(kicad_pcb
	(version 20260206)
	(generator "pcbnew")
	(generator_version "10.0")
	(general
		(thickness 1.6)
		(legacy_teardrops no)
	)
	(paper "A4")
	(title_block
		(title "01162023_DA0F0TEBIF0_F0T_Expander_BD_F_brd_V02_OCP.brd")
		(comment 1 "Grand Teton / footprints 8622-8631 of 9728")
	)
	(layers
		(0 "F.Cu" signal "TOP")
		(4 "In1.Cu" signal "GND")
		(6 "In2.Cu" signal "VCC")
		(8 "In3.Cu" signal "VCC1")
		(10 "In4.Cu" signal "GND1")
		(12 "In5.Cu" signal "IN1")
		(14 "In6.Cu" signal "GND2")
		(16 "In7.Cu" signal "IN2")
		(18 "In8.Cu" signal "GND3")
		(20 "In9.Cu" signal "IN3")
		(22 "In10.Cu" signal "GND4")
		(24 "In11.Cu" signal "IN4")
		(26 "In12.Cu" signal "GND5")
		(28 "In13.Cu" signal "IN5")
		(30 "In14.Cu" signal "GND6")
		(32 "In15.Cu" signal "IN6")
		(34 "In16.Cu" signal "GND7")
		(2 "B.Cu" signal "BOTTOM")
		(9 "F.Adhes" user "F.Adhesive")
		(11 "B.Adhes" user "B.Adhesive")
		(13 "F.Paste" user "Package Geometry/Pastemask Top")
		(15 "B.Paste" user "Package Geometry/Pastemask Bottom")
		(5 "F.SilkS" user "Ref Des/Silkscreen Top")
		(7 "B.SilkS" user "Ref Des/Silkscreen Bottom")
		(1 "F.Mask" user "Board Geometry/Soldermask Top")
		(3 "B.Mask" user "Board Geometry/Soldermask Bottom")
		(17 "Dwgs.User" user "User.Drawings")
		(19 "Cmts.User" user "User.Comments")
		(21 "Eco1.User" user "User.Eco1")
		(23 "Eco2.User" user "User.Eco2")
		(25 "Edge.Cuts" user "Board Geometry/Outline")
		(27 "Margin" user)
		(31 "F.CrtYd" user "Package Geometry/Place Bound Top")
		(29 "B.CrtYd" user "Package Geometry/Place Bound Bottom")
		(35 "F.Fab" user "Ref Des/Assembly Top")
		(33 "B.Fab" user "Ref Des/Assembly Bottom")
	)
	(footprint ""
		(layer "B.Cu")
		(at 114.641122 -325.175626 -90)
		(property "Reference" "C4212"
			(at 0 0 90)
			(layer "B.SilkS")
			(hide yes)
			(effects
				(font
					(size 1.27 1.27)
				)
				(justify mirror)
			)
		)
		(property "Value" ""
			(at 0 0 90)
			(layer "B.Fab")
			(effects
				(font
					(size 1.27 1.27)
				)
				(justify mirror)
			)
		)
		(duplicate_pad_numbers_are_jumpers no)
		(fp_line
			(start -1.2954 0.5842)
			(end 1.2954 0.5842)
			(stroke
				(width 0.1524)
				(type default)
			)
			(layer "B.SilkS")
		)
		(fp_line
			(start 1.2954 0.5842)
			(end 1.2954 -0.5842)
			(stroke
				(width 0.1524)
				(type default)
			)
			(layer "B.SilkS")
		)
		(fp_line
			(start -1.2954 -0.5842)
			(end -1.2954 0.5842)
			(stroke
				(width 0.1524)
				(type default)
			)
			(layer "B.SilkS")
		)
		(fp_line
			(start 1.2954 -0.5842)
			(end -1.2954 -0.5842)
			(stroke
				(width 0.1524)
				(type default)
			)
			(layer "B.SilkS")
		)
		(fp_line
			(start -0.8636 0.4572)
			(end 0.8636 0.4572)
			(stroke
				(width 0.1)
				(type default)
			)
			(layer "B.Fab")
		)
		(fp_line
			(start 0.8636 0.4572)
			(end 0.8636 0.4064)
			(stroke
				(width 0.1)
				(type default)
			)
			(layer "B.Fab")
		)
		(fp_line
			(start -1.1938 0.4064)
			(end -0.8636 0.4064)
			(stroke
				(width 0.1)
				(type default)
			)
			(layer "B.Fab")
		)
		(fp_line
			(start -0.8636 0.4064)
			(end -0.8636 0.4572)
			(stroke
				(width 0.1)
				(type default)
			)
			(layer "B.Fab")
		)
		(fp_line
			(start 0.8636 0.4064)
			(end 1.1938 0.4064)
			(stroke
				(width 0.1)
				(type default)
			)
			(layer "B.Fab")
		)
		(fp_line
			(start 1.1938 0.4064)
			(end 1.1938 -0.4064)
			(stroke
				(width 0.1)
				(type default)
			)
			(layer "B.Fab")
		)
		(fp_line
			(start -1.1938 -0.4064)
			(end -1.1938 0.4064)
			(stroke
				(width 0.1)
				(type default)
			)
			(layer "B.Fab")
		)
		(fp_line
			(start -0.8636 -0.4064)
			(end -1.1938 -0.4064)
			(stroke
				(width 0.1)
				(type default)
			)
			(layer "B.Fab")
		)
		(fp_line
			(start 0.8636 -0.4064)
			(end 0.8636 -0.4572)
			(stroke
				(width 0.1)
				(type default)
			)
			(layer "B.Fab")
		)
		(fp_line
			(start 1.1938 -0.4064)
			(end 0.8636 -0.4064)
			(stroke
				(width 0.1)
				(type default)
			)
			(layer "B.Fab")
		)
		(fp_line
			(start -0.8636 -0.4572)
			(end -0.8636 -0.4064)
			(stroke
				(width 0.1)
				(type default)
			)
			(layer "B.Fab")
		)
		(fp_line
			(start 0.8636 -0.4572)
			(end -0.8636 -0.4572)
			(stroke
				(width 0.1)
				(type default)
			)
			(layer "B.Fab")
		)
		(pad "1" smd rect
			(at 0.7366 0 180)
			(size 0.7112 0.8128)
			(layers "B.Cu" "B.Mask" "B.Paste")
			(net "P0V8_SERDES_VDDA_PEX0_C6")
		)
		(pad "2" smd rect
			(at -0.7366 0 180)
			(size 0.7112 0.8128)
			(layers "B.Cu" "B.Mask" "B.Paste")
			(net "GND")
		)
	)
	(footprint ""
		(layer "B.Cu")
		(at 389.89 -236.728 -90)
		(property "Reference" "C2566"
			(at 0 0 90)
			(layer "B.SilkS")
			(hide yes)
			(effects
				(font
					(size 1.27 1.27)
				)
				(justify mirror)
			)
		)
		(property "Value" ""
			(at 0 0 90)
			(layer "B.Fab")
			(effects
				(font
					(size 1.27 1.27)
				)
				(justify mirror)
			)
		)
		(duplicate_pad_numbers_are_jumpers no)
		(fp_line
			(start -0.7874 0.4064)
			(end 0.7874 0.4064)
			(stroke
				(width 0.1524)
				(type default)
			)
			(layer "B.SilkS")
		)
		(fp_line
			(start 0.7874 0.4064)
			(end 0.7874 -0.4064)
			(stroke
				(width 0.1524)
				(type default)
			)
			(layer "B.SilkS")
		)
		(fp_line
			(start -0.7874 -0.4064)
			(end -0.7874 0.4064)
			(stroke
				(width 0.1524)
				(type default)
			)
			(layer "B.SilkS")
		)
		(fp_line
			(start 0.7874 -0.4064)
			(end -0.7874 -0.4064)
			(stroke
				(width 0.1524)
				(type default)
			)
			(layer "B.SilkS")
		)
		(fp_line
			(start -0.67945 0.3048)
			(end -0.120396 0.3048)
			(stroke
				(width 0.1)
				(type default)
			)
			(layer "B.Fab")
		)
		(fp_line
			(start -0.120396 0.3048)
			(end -0.120396 0.2794)
			(stroke
				(width 0.1)
				(type default)
			)
			(layer "B.Fab")
		)
		(fp_line
			(start 0.12065 0.3048)
			(end 0.67945 0.3048)
			(stroke
				(width 0.1)
				(type default)
			)
			(layer "B.Fab")
		)
		(fp_line
			(start 0.67945 0.3048)
			(end 0.67945 -0.305054)
			(stroke
				(width 0.1)
				(type default)
			)
			(layer "B.Fab")
		)
		(fp_line
			(start -0.120396 0.2794)
			(end 0.12065 0.2794)
			(stroke
				(width 0.1)
				(type default)
			)
			(layer "B.Fab")
		)
		(fp_line
			(start 0.12065 0.2794)
			(end 0.12065 0.3048)
			(stroke
				(width 0.1)
				(type default)
			)
			(layer "B.Fab")
		)
		(fp_line
			(start -0.12065 -0.2794)
			(end -0.12065 -0.3048)
			(stroke
				(width 0.1)
				(type default)
			)
			(layer "B.Fab")
		)
		(fp_line
			(start 0.12065 -0.2794)
			(end -0.12065 -0.2794)
			(stroke
				(width 0.1)
				(type default)
			)
			(layer "B.Fab")
		)
		(fp_line
			(start -0.67945 -0.3048)
			(end -0.67945 0.3048)
			(stroke
				(width 0.1)
				(type default)
			)
			(layer "B.Fab")
		)
		(fp_line
			(start -0.12065 -0.3048)
			(end -0.67945 -0.3048)
			(stroke
				(width 0.1)
				(type default)
			)
			(layer "B.Fab")
		)
		(fp_line
			(start 0.12065 -0.305054)
			(end 0.12065 -0.2794)
			(stroke
				(width 0.1)
				(type default)
			)
			(layer "B.Fab")
		)
		(fp_line
			(start 0.67945 -0.305054)
			(end 0.12065 -0.305054)
			(stroke
				(width 0.1)
				(type default)
			)
			(layer "B.Fab")
		)
		(pad "1" smd circle
			(at 0.40005 0 90)
			(size 0 0)
			(layers "B.Cu" "B.Mask" "B.Paste")
			(net "P3V3_AUX")
		)
		(pad "2" smd circle
			(at -0.40005 0 90)
			(size 0 0)
			(layers "B.Cu" "B.Mask" "B.Paste")
			(net "GND")
		)
	)
	(footprint ""
		(layer "B.Cu")
		(at 406.999948 -292.099746 90)
		(property "Reference" "C1926"
			(at 0 0 90)
			(layer "B.SilkS")
			(hide yes)
			(effects
				(font
					(size 1.27 1.27)
				)
				(justify mirror)
			)
		)
		(property "Value" ""
			(at 0 0 90)
			(layer "B.Fab")
			(effects
				(font
					(size 1.27 1.27)
				)
				(justify mirror)
			)
		)
		(duplicate_pad_numbers_are_jumpers no)
		(fp_line
			(start 0.299974 -0.150114)
			(end -0.299974 -0.150114)
			(stroke
				(width 0.1)
				(type default)
			)
			(layer "B.Fab")
		)
		(fp_line
			(start -0.299974 -0.150114)
			(end -0.299974 0.150114)
			(stroke
				(width 0.1)
				(type default)
			)
			(layer "B.Fab")
		)
		(fp_line
			(start 0.299974 0.150114)
			(end 0.299974 -0.150114)
			(stroke
				(width 0.1)
				(type default)
			)
			(layer "B.Fab")
		)
		(fp_line
			(start -0.299974 0.150114)
			(end 0.299974 0.150114)
			(stroke
				(width 0.1)
				(type default)
			)
			(layer "B.Fab")
		)
		(pad "1" smd rect
			(at 0.2667 0 270)
			(size 0.3048 0.381)
			(layers "B.Cu" "B.Mask" "B.Paste")
			(net "P0V8_SERDES_VDDA_PEX3")
		)
		(pad "2" smd rect
			(at -0.2667 0 270)
			(size 0.3048 0.381)
			(layers "B.Cu" "B.Mask" "B.Paste")
			(net "GND")
		)
	)
	(footprint ""
		(layer "B.Cu")
		(at 57.274968 -286.399732 90)
		(property "Reference" "C2951"
			(at 0 0 90)
			(layer "B.SilkS")
			(hide yes)
			(effects
				(font
					(size 1.27 1.27)
				)
				(justify mirror)
			)
		)
		(property "Value" ""
			(at 0 0 90)
			(layer "B.Fab")
			(effects
				(font
					(size 1.27 1.27)
				)
				(justify mirror)
			)
		)
		(duplicate_pad_numbers_are_jumpers no)
		(fp_line
			(start 0.299974 -0.150114)
			(end -0.299974 -0.150114)
			(stroke
				(width 0.1)
				(type default)
			)
			(layer "B.Fab")
		)
		(fp_line
			(start -0.299974 -0.150114)
			(end -0.299974 0.150114)
			(stroke
				(width 0.1)
				(type default)
			)
			(layer "B.Fab")
		)
		(fp_line
			(start 0.299974 0.150114)
			(end 0.299974 -0.150114)
			(stroke
				(width 0.1)
				(type default)
			)
			(layer "B.Fab")
		)
		(fp_line
			(start -0.299974 0.150114)
			(end 0.299974 0.150114)
			(stroke
				(width 0.1)
				(type default)
			)
			(layer "B.Fab")
		)
		(pad "1" smd rect
			(at 0.2667 0 270)
			(size 0.3048 0.381)
			(layers "B.Cu" "B.Mask" "B.Paste")
			(net "P1V25_SERDES_VDDPLL_PEX0")
		)
		(pad "2" smd rect
			(at -0.2667 0 270)
			(size 0.3048 0.381)
			(layers "B.Cu" "B.Mask" "B.Paste")
			(net "GND")
		)
	)
	(footprint ""
		(layer "B.Cu")
		(at 29.741622 -225.76663 180)
		(property "Reference" "R6163"
			(at 0 0 0)
			(layer "B.SilkS")
			(hide yes)
			(effects
				(font
					(size 1.27 1.27)
				)
				(justify mirror)
			)
		)
		(property "Value" ""
			(at 0 0 0)
			(layer "B.Fab")
			(effects
				(font
					(size 1.27 1.27)
				)
				(justify mirror)
			)
		)
		(duplicate_pad_numbers_are_jumpers no)
		(fp_line
			(start 0.7874 0.4064)
			(end 0.7874 -0.4064)
			(stroke
				(width 0.1524)
				(type default)
			)
			(layer "B.SilkS")
		)
		(fp_line
			(start 0.7874 -0.4064)
			(end -0.7874 -0.4064)
			(stroke
				(width 0.1524)
				(type default)
			)
			(layer "B.SilkS")
		)
		(fp_line
			(start -0.7874 0.4064)
			(end 0.7874 0.4064)
			(stroke
				(width 0.1524)
				(type default)
			)
			(layer "B.SilkS")
		)
		(fp_line
			(start -0.7874 -0.4064)
			(end -0.7874 0.4064)
			(stroke
				(width 0.1524)
				(type default)
			)
			(layer "B.SilkS")
		)
		(fp_line
			(start 0.67945 0.3048)
			(end 0.67945 -0.305054)
			(stroke
				(width 0.1)
				(type default)
			)
			(layer "B.Fab")
		)
		(fp_line
			(start 0.67945 -0.305054)
			(end 0.12065 -0.305054)
			(stroke
				(width 0.1)
				(type default)
			)
			(layer "B.Fab")
		)
		(fp_line
			(start 0.12065 0.3048)
			(end 0.67945 0.3048)
			(stroke
				(width 0.1)
				(type default)
			)
			(layer "B.Fab")
		)
		(fp_line
			(start 0.12065 0.2794)
			(end 0.12065 0.3048)
			(stroke
				(width 0.1)
				(type default)
			)
			(layer "B.Fab")
		)
		(fp_line
			(start 0.12065 -0.2794)
			(end -0.12065 -0.2794)
			(stroke
				(width 0.1)
				(type default)
			)
			(layer "B.Fab")
		)
		(fp_line
			(start 0.12065 -0.305054)
			(end 0.12065 -0.2794)
			(stroke
				(width 0.1)
				(type default)
			)
			(layer "B.Fab")
		)
		(fp_line
			(start -0.120396 0.3048)
			(end -0.120396 0.2794)
			(stroke
				(width 0.1)
				(type default)
			)
			(layer "B.Fab")
		)
		(fp_line
			(start -0.120396 0.2794)
			(end 0.12065 0.2794)
			(stroke
				(width 0.1)
				(type default)
			)
			(layer "B.Fab")
		)
		(fp_line
			(start -0.12065 -0.2794)
			(end -0.12065 -0.3048)
			(stroke
				(width 0.1)
				(type default)
			)
			(layer "B.Fab")
		)
		(fp_line
			(start -0.12065 -0.3048)
			(end -0.67945 -0.3048)
			(stroke
				(width 0.1)
				(type default)
			)
			(layer "B.Fab")
		)
		(fp_line
			(start -0.67945 0.3048)
			(end -0.120396 0.3048)
			(stroke
				(width 0.1)
				(type default)
			)
			(layer "B.Fab")
		)
		(fp_line
			(start -0.67945 -0.3048)
			(end -0.67945 0.3048)
			(stroke
				(width 0.1)
				(type default)
			)
			(layer "B.Fab")
		)
		(pad "1" smd circle
			(at 0.40005 0)
			(size 0 0)
			(layers "B.Cu" "B.Mask" "B.Paste")
			(net "SPI_PEX0_RST_R_N")
		)
		(pad "2" smd circle
			(at -0.40005 0)
			(size 0 0)
			(layers "B.Cu" "B.Mask" "B.Paste")
			(net "P1V8_PEX")
		)
	)
	(footprint ""
		(layer "B.Cu")
		(at 282.824936 -297.79976 -90)
		(property "Reference" "C1662"
			(at 0 0 90)
			(layer "B.SilkS")
			(hide yes)
			(effects
				(font
					(size 1.27 1.27)
				)
				(justify mirror)
			)
		)
		(property "Value" ""
			(at 0 0 90)
			(layer "B.Fab")
			(effects
				(font
					(size 1.27 1.27)
				)
				(justify mirror)
			)
		)
		(duplicate_pad_numbers_are_jumpers no)
		(fp_line
			(start -0.299974 0.150114)
			(end 0.299974 0.150114)
			(stroke
				(width 0.1)
				(type default)
			)
			(layer "B.Fab")
		)
		(fp_line
			(start 0.299974 0.150114)
			(end 0.299974 -0.150114)
			(stroke
				(width 0.1)
				(type default)
			)
			(layer "B.Fab")
		)
		(fp_line
			(start -0.299974 -0.150114)
			(end -0.299974 0.150114)
			(stroke
				(width 0.1)
				(type default)
			)
			(layer "B.Fab")
		)
		(fp_line
			(start 0.299974 -0.150114)
			(end -0.299974 -0.150114)
			(stroke
				(width 0.1)
				(type default)
			)
			(layer "B.Fab")
		)
		(pad "1" smd rect
			(at 0.2667 0 90)
			(size 0.3048 0.381)
			(layers "B.Cu" "B.Mask" "B.Paste")
			(net "P0V8_PEX2")
		)
		(pad "2" smd rect
			(at -0.2667 0 90)
			(size 0.3048 0.381)
			(layers "B.Cu" "B.Mask" "B.Paste")
			(net "GND")
		)
	)
	(footprint ""
		(layer "B.Cu")
		(at 301.824898 -304.241454 90)
		(property "Reference" "C3359"
			(at 0 0 90)
			(layer "B.SilkS")
			(hide yes)
			(effects
				(font
					(size 1.27 1.27)
				)
				(justify mirror)
			)
		)
		(property "Value" ""
			(at 0 0 90)
			(layer "B.Fab")
			(effects
				(font
					(size 1.27 1.27)
				)
				(justify mirror)
			)
		)
		(duplicate_pad_numbers_are_jumpers no)
		(fp_line
			(start 0.299974 -0.150114)
			(end -0.299974 -0.150114)
			(stroke
				(width 0.1)
				(type default)
			)
			(layer "B.Fab")
		)
		(fp_line
			(start -0.299974 -0.150114)
			(end -0.299974 0.150114)
			(stroke
				(width 0.1)
				(type default)
			)
			(layer "B.Fab")
		)
		(fp_line
			(start 0.299974 0.150114)
			(end 0.299974 -0.150114)
			(stroke
				(width 0.1)
				(type default)
			)
			(layer "B.Fab")
		)
		(fp_line
			(start -0.299974 0.150114)
			(end 0.299974 0.150114)
			(stroke
				(width 0.1)
				(type default)
			)
			(layer "B.Fab")
		)
		(pad "1" smd rect
			(at 0.2667 0 270)
			(size 0.3048 0.381)
			(layers "B.Cu" "B.Mask" "B.Paste")
			(net "P1V8_VDDA_PEX2")
		)
		(pad "2" smd rect
			(at -0.2667 0 270)
			(size 0.3048 0.381)
			(layers "B.Cu" "B.Mask" "B.Paste")
			(net "GND")
		)
	)
	(footprint ""
		(layer "B.Cu")
		(at 58.177176 -286.399732 90)
		(property "Reference" "C2958"
			(at 0 0 90)
			(layer "B.SilkS")
			(hide yes)
			(effects
				(font
					(size 1.27 1.27)
				)
				(justify mirror)
			)
		)
		(property "Value" ""
			(at 0 0 90)
			(layer "B.Fab")
			(effects
				(font
					(size 1.27 1.27)
				)
				(justify mirror)
			)
		)
		(duplicate_pad_numbers_are_jumpers no)
		(fp_line
			(start 0.299974 -0.150114)
			(end -0.299974 -0.150114)
			(stroke
				(width 0.1)
				(type default)
			)
			(layer "B.Fab")
		)
		(fp_line
			(start -0.299974 -0.150114)
			(end -0.299974 0.150114)
			(stroke
				(width 0.1)
				(type default)
			)
			(layer "B.Fab")
		)
		(fp_line
			(start 0.299974 0.150114)
			(end 0.299974 -0.150114)
			(stroke
				(width 0.1)
				(type default)
			)
			(layer "B.Fab")
		)
		(fp_line
			(start -0.299974 0.150114)
			(end 0.299974 0.150114)
			(stroke
				(width 0.1)
				(type default)
			)
			(layer "B.Fab")
		)
		(pad "1" smd rect
			(at 0.2667 0 270)
			(size 0.3048 0.381)
			(layers "B.Cu" "B.Mask" "B.Paste")
			(net "P1V25_SERDES_VDDPLL_PEX0")
		)
		(pad "2" smd rect
			(at -0.2667 0 270)
			(size 0.3048 0.381)
			(layers "B.Cu" "B.Mask" "B.Paste")
			(net "GND")
		)
	)
	(footprint ""
		(layer "B.Cu")
		(at 340.494112 -217.187018 -90)
		(property "Reference" "C2057"
			(at 0 0 90)
			(layer "B.SilkS")
			(hide yes)
			(effects
				(font
					(size 1.27 1.27)
				)
				(justify mirror)
			)
		)
		(property "Value" ""
			(at 0 0 90)
			(layer "B.Fab")
			(effects
				(font
					(size 1.27 1.27)
				)
				(justify mirror)
			)
		)
		(duplicate_pad_numbers_are_jumpers no)
		(fp_line
			(start -0.69215 0.2921)
			(end 0.69215 0.2921)
			(stroke
				(width 0.1524)
				(type default)
			)
			(layer "B.SilkS")
		)
		(fp_line
			(start 0.69215 0.2921)
			(end 0.69215 -0.2921)
			(stroke
				(width 0.1524)
				(type default)
			)
			(layer "B.SilkS")
		)
		(fp_line
			(start -0.69215 -0.2921)
			(end -0.69215 0.2921)
			(stroke
				(width 0.1524)
				(type default)
			)
			(layer "B.SilkS")
		)
		(fp_line
			(start 0.69215 -0.2921)
			(end -0.69215 -0.2921)
			(stroke
				(width 0.1524)
				(type default)
			)
			(layer "B.SilkS")
		)
		(fp_line
			(start -0.51435 0.2794)
			(end 0.51435 0.2794)
			(stroke
				(width 0.1)
				(type default)
			)
			(layer "B.Fab")
		)
		(fp_line
			(start 0.51435 0.2794)
			(end 0.51435 -0.2794)
			(stroke
				(width 0.1)
				(type default)
			)
			(layer "B.Fab")
		)
		(fp_line
			(start -0.51435 -0.2794)
			(end -0.51435 0.2794)
			(stroke
				(width 0.1)
				(type default)
			)
			(layer "B.Fab")
		)
		(fp_line
			(start 0.51435 -0.2794)
			(end -0.51435 -0.2794)
			(stroke
				(width 0.1)
				(type default)
			)
			(layer "B.Fab")
		)
		(pad "1" smd circle
			(at 0.40005 0 90)
			(size 0 0)
			(layers "B.Cu" "B.Mask" "B.Paste")
			(net "P3V3_FPGA_VCCIO2")
		)
		(pad "2" smd circle
			(at -0.40005 0 90)
			(size 0 0)
			(layers "B.Cu" "B.Mask" "B.Paste")
			(net "GND")
		)
		(zone
			(layer "B.Cu")
			(hatch none 0.5)
			(connect_pads
				(clearance 0)
			)
			(min_thickness 0.25)
			(keepout
				(tracks not_allowed)
				(vias allowed)
				(pads allowed)
				(copperpour not_allowed)
				(footprints allowed)
			)
			(placement
				(enabled no)
				(sheetname "")
			)
			(fill
				(thermal_gap 0.5)
				(thermal_bridge_width 0.5)
				(island_removal_mode 0)
			)
			(polygon
				(pts
					(xy 340.406482 -216.996518) (xy 340.348316 -217.087958) (xy 340.348316 -217.287348) (xy 340.406482 -217.377518)
					(xy 340.581742 -217.377518) (xy 340.640162 -217.287348) (xy 340.640162 -217.087958) (xy 340.581996 -216.996518)
				)
			)
		)
	)
	(footprint ""
		(layer "B.Cu")
		(at 231.410002 -256.168144)
		(property "Reference" "C4350"
			(at 0 0 0)
			(layer "B.SilkS")
			(hide yes)
			(effects
				(font
					(size 1.27 1.27)
				)
				(justify mirror)
			)
		)
		(property "Value" ""
			(at 0 0 0)
			(layer "B.Fab")
			(effects
				(font
					(size 1.27 1.27)
				)
				(justify mirror)
			)
		)
		(duplicate_pad_numbers_are_jumpers no)
		(fp_line
			(start -0.299974 -0.150114)
			(end -0.299974 0.150114)
			(stroke
				(width 0.1)
				(type default)
			)
			(layer "B.Fab")
		)
		(fp_line
			(start -0.299974 0.150114)
			(end 0.299974 0.150114)
			(stroke
				(width 0.1)
				(type default)
			)
			(layer "B.Fab")
		)
		(fp_line
			(start 0.299974 -0.150114)
			(end -0.299974 -0.150114)
			(stroke
				(width 0.1)
				(type default)
			)
			(layer "B.Fab")
		)
		(fp_line
			(start 0.299974 0.150114)
			(end 0.299974 -0.150114)
			(stroke
				(width 0.1)
				(type default)
			)
			(layer "B.Fab")
		)
		(pad "1" smd rect
			(at 0.2667 0 180)
			(size 0.3048 0.381)
			(layers "B.Cu" "B.Mask" "B.Paste")
			(net "P1V25_SERDES_VDDPLL_PEX2")
		)
		(pad "2" smd rect
			(at -0.2667 0 180)
			(size 0.3048 0.381)
			(layers "B.Cu" "B.Mask" "B.Paste")
			(net "GND")
		)
	)
)
